(kicad_pcb
	(version 20260206)
	(generator "pcbnew")
	(generator_version "10.0")
	(general
		(thickness 1.6)
		(legacy_teardrops no)
	)
	(paper "A4")
	(title_block
		(title "peb — Lightning_PEB_BRD.brd")
		(comment 1 "Lightning (Wiwynn / Facebook NVMe JBOF) / footprints 573-577 of 2563")
	)
	(layers
		(0 "F.Cu" signal "TOP")
		(4 "In1.Cu" signal "L2GND")
		(6 "In2.Cu" signal "L3")
		(8 "In3.Cu" signal "L4VCC")
		(10 "In4.Cu" signal "L5VCC")
		(12 "In5.Cu" signal "L6")
		(14 "In6.Cu" signal "L7GND")
		(2 "B.Cu" signal "BOTTOM")
		(9 "F.Adhes" user "F.Adhesive")
		(11 "B.Adhes" user "B.Adhesive")
		(13 "F.Paste" user "Package Geometry/Pastemask Top")
		(15 "B.Paste" user "Package Geometry/Pastemask Bottom")
		(5 "F.SilkS" user "Ref Des/Silkscreen Top")
		(7 "B.SilkS" user "Ref Des/Silkscreen Bottom")
		(1 "F.Mask" user "Board Geometry/Soldermask Top")
		(3 "B.Mask" user "Board Geometry/Soldermask Bottom")
		(17 "Dwgs.User" user "User.Drawings")
		(19 "Cmts.User" user "User.Comments")
		(21 "Eco1.User" user "User.Eco1")
		(23 "Eco2.User" user "User.Eco2")
		(25 "Edge.Cuts" user "Board Geometry/Outline")
		(27 "Margin" user)
		(31 "F.CrtYd" user "Package Geometry/Place Bound Top")
		(29 "B.CrtYd" user "Package Geometry/Place Bound Bottom")
		(35 "F.Fab" user "Ref Des/Assembly Top")
		(33 "B.Fab" user "Ref Des/Assembly Bottom")
	)
	(footprint ""
		(layer "F.Cu")
		(at 50.423572 -57.303924)
		(property "Reference" "SKT6"
			(at 0 0 0)
			(layer "F.SilkS")
			(hide yes)
			(effects
				(font
					(size 1.27 1.27)
				)
			)
		)
		(property "Value" "SKT-SPI8P-9-GP"
			(at 6.989318 7.128764 0)
			(unlocked yes)
			(layer "F.Fab")
			(hide yes)
			(effects
				(font
					(size 1.016 1.016)
					(thickness 0.1524)
				)
			)
		)
		(property "Device Type" "SKT-SOIC8-104117H235"
			(at 6.989318 5.604764 0)
			(unlocked yes)
			(layer "F.Fab")
			(hide yes)
			(effects
				(font
					(size 1.016 1.016)
					(thickness 0.1524)
				)
			)
		)
		(duplicate_pad_numbers_are_jumpers no)
		(fp_line
			(start -5.4483 -1.416304)
			(end -4.0513 -3.334004)
			(stroke
				(width 0.1524)
				(type default)
			)
			(layer "F.SilkS")
		)
		(fp_line
			(start -5.4483 1.416304)
			(end -5.4483 -1.416304)
			(stroke
				(width 0.1524)
				(type default)
			)
			(layer "F.SilkS")
		)
		(fp_line
			(start -4.0513 -5.8293)
			(end 4.0513 -5.8293)
			(stroke
				(width 0.1524)
				(type default)
			)
			(layer "F.SilkS")
		)
		(fp_line
			(start -4.0513 -3.334004)
			(end -4.0513 -5.8293)
			(stroke
				(width 0.1524)
				(type default)
			)
			(layer "F.SilkS")
		)
		(fp_line
			(start -4.0513 3.334004)
			(end -5.4483 1.416304)
			(stroke
				(width 0.1524)
				(type default)
			)
			(layer "F.SilkS")
		)
		(fp_line
			(start -4.0513 5.8293)
			(end -4.0513 3.334004)
			(stroke
				(width 0.1524)
				(type default)
			)
			(layer "F.SilkS")
		)
		(fp_line
			(start 3.8735 -5.6515)
			(end 3.8735 -3.6449)
			(stroke
				(width 0.508)
				(type default)
			)
			(layer "F.SilkS")
		)
		(fp_line
			(start 4.0513 -5.8293)
			(end 4.0513 -3.334004)
			(stroke
				(width 0.1524)
				(type default)
			)
			(layer "F.SilkS")
		)
		(fp_line
			(start 4.0513 -3.334004)
			(end 5.4483 -1.416304)
			(stroke
				(width 0.1524)
				(type default)
			)
			(layer "F.SilkS")
		)
		(fp_line
			(start 4.0513 3.334004)
			(end 4.0513 5.8293)
			(stroke
				(width 0.1524)
				(type default)
			)
			(layer "F.SilkS")
		)
		(fp_line
			(start 4.0513 5.8293)
			(end -4.0513 5.8293)
			(stroke
				(width 0.1524)
				(type default)
			)
			(layer "F.SilkS")
		)
		(fp_line
			(start 4.6736 0)
			(end 5.4356 -0.762)
			(stroke
				(width 0.1524)
				(type default)
			)
			(layer "F.SilkS")
		)
		(fp_line
			(start 5.4356 0.762)
			(end 4.6736 0)
			(stroke
				(width 0.1524)
				(type default)
			)
			(layer "F.SilkS")
		)
		(fp_line
			(start 5.4483 -1.416304)
			(end 5.4483 1.416304)
			(stroke
				(width 0.1524)
				(type default)
			)
			(layer "F.SilkS")
		)
		(fp_line
			(start 5.4483 1.416304)
			(end 4.0513 3.334004)
			(stroke
				(width 0.1524)
				(type default)
			)
			(layer "F.SilkS")
		)
		(fp_poly
			(pts
				(xy -2.159 3.047492) (xy 2.159 3.047492) (xy 2.159 -3.047492) (xy -2.159 -3.047492)
			)
			(stroke
				(width 0)
				(type default)
			)
			(fill yes)
			(layer "F.SilkS")
		)
		(fp_rect
			(start -5.7023 -5.8293)
			(end 5.7023 -10.5156)
			(stroke
				(width 0)
				(type default)
			)
			(fill no)
			(layer "F.CrtYd")
		)
		(fp_rect
			(start -5.7023 9.7282)
			(end 5.7023 5.8293)
			(stroke
				(width 0)
				(type default)
			)
			(fill no)
			(layer "F.CrtYd")
		)
		(fp_poly
			(pts
				(xy -5.7023 5.8293) (xy -5.7023 -5.8293) (xy -3.7973 -5.8293) (xy -3.7973 -3.2512) (xy -5.1943 -1.3335)
				(xy -5.1943 1.3335) (xy -3.7973 3.2512) (xy -3.7973 5.8293)
			)
			(stroke
				(width 0)
				(type default)
			)
			(fill no)
			(layer "F.CrtYd")
		)
		(fp_poly
			(pts
				(xy 3.7973 5.8293) (xy 3.7973 3.2512) (xy 5.1943 1.3335) (xy 5.1943 -1.3335) (xy 3.7973 -3.2512)
				(xy 3.7973 -5.8293) (xy 5.7023 -5.8293) (xy 5.7023 5.8293)
			)
			(stroke
				(width 0)
				(type default)
			)
			(fill no)
			(layer "F.CrtYd")
		)
		(fp_poly
			(pts
				(xy -3.7973 5.8293) (xy -3.7973 3.2512) (xy -5.1943 1.3335) (xy -5.1943 -1.3335) (xy -3.7973 -3.2512)
				(xy -3.7973 -5.8293) (xy 3.7973 -5.8293) (xy 3.7973 -3.2512) (xy 5.1943 -1.3335) (xy 5.1943 1.3335)
				(xy 3.7973 3.2512) (xy 3.7973 5.8293)
			)
			(stroke
				(width 0)
				(type default)
			)
			(fill no)
			(layer "F.CrtYd")
		)
		(fp_rect
			(start -5.7023 9.7282)
			(end 5.7023 -10.5156)
			(stroke
				(width 0)
				(type default)
			)
			(fill no)
			(layer "F.Fab")
		)
		(pad "1" smd rect
			(at 1.905 -3.999992)
			(size 0.508 1.4986)
			(layers "F.Cu" "F.Mask" "F.Paste")
			(net "NVM_CS_N_R")
		)
		(pad "2" smd rect
			(at 0.635 -3.999992)
			(size 0.508 1.4986)
			(layers "F.Cu" "F.Mask" "F.Paste")
			(net "NVM_SO_R")
		)
		(pad "3" smd rect
			(at -0.635 -3.999992)
			(size 0.508 1.4986)
			(layers "F.Cu" "F.Mask" "F.Paste")
			(net "U44_WP_N")
		)
		(pad "4" smd rect
			(at -1.905 -3.999992)
			(size 0.508 1.4986)
			(layers "F.Cu" "F.Mask" "F.Paste")
			(net "GND")
		)
		(pad "5" smd rect
			(at -1.905 3.999992)
			(size 0.508 1.4986)
			(layers "F.Cu" "F.Mask" "F.Paste")
			(net "NVM_SI_R")
		)
		(pad "6" smd rect
			(at -0.635 3.999992)
			(size 0.508 1.4986)
			(layers "F.Cu" "F.Mask" "F.Paste")
			(net "NVM_SK_R")
		)
		(pad "7" smd rect
			(at 0.635 3.999992)
			(size 0.508 1.4986)
			(layers "F.Cu" "F.Mask" "F.Paste")
			(net "U44_HOLD_N")
		)
		(pad "8" smd rect
			(at 1.905 3.999992)
			(size 0.508 1.4986)
			(layers "F.Cu" "F.Mask" "F.Paste")
			(net "P3V3_STBY")
		)
		(zone
			(layer "F.Cu")
			(hatch none 0.5)
			(connect_pads
				(clearance 0)
			)
			(min_thickness 0.25)
			(keepout
				(tracks allowed)
				(vias not_allowed)
				(pads allowed)
				(copperpour not_allowed)
				(footprints allowed)
			)
			(placement
				(enabled no)
				(sheetname "")
			)
			(fill
				(thermal_gap 0.5)
				(thermal_bridge_width 0.5)
				(island_removal_mode 0)
			)
			(polygon
				(pts
					(xy 48.264572 -60.046616) (xy 52.582572 -60.046616) (xy 52.582572 -60.554616) (xy 48.264572 -60.554616)
				)
			)
		)
		(zone
			(layer "F.Cu")
			(hatch none 0.5)
			(connect_pads
				(clearance 0)
			)
			(min_thickness 0.25)
			(keepout
				(tracks allowed)
				(vias not_allowed)
				(pads allowed)
				(copperpour not_allowed)
				(footprints allowed)
			)
			(placement
				(enabled no)
				(sheetname "")
			)
			(fill
				(thermal_gap 0.5)
				(thermal_bridge_width 0.5)
				(island_removal_mode 0)
			)
			(polygon
				(pts
					(xy 48.264572 -54.053232) (xy 52.582572 -54.053232) (xy 52.582572 -60.554616) (xy 48.264572 -60.554616)
				)
			)
		)
		(zone
			(layer "F.Cu")
			(hatch none 0.5)
			(connect_pads
				(clearance 0)
			)
			(min_thickness 0.25)
			(keepout
				(tracks not_allowed)
				(vias allowed)
				(pads allowed)
				(copperpour not_allowed)
				(footprints allowed)
			)
			(placement
				(enabled no)
				(sheetname "")
			)
			(fill
				(thermal_gap 0.5)
				(thermal_bridge_width 0.5)
				(island_removal_mode 0)
			)
			(polygon
				(pts
					(xy 48.264572 -54.053232) (xy 52.582572 -54.053232) (xy 52.582572 -60.554616) (xy 48.264572 -60.554616)
				)
			)
		)
		(zone
			(layer "F.Cu")
			(hatch none 0.5)
			(connect_pads
				(clearance 0)
			)
			(min_thickness 0.25)
			(keepout
				(tracks allowed)
				(vias not_allowed)
				(pads allowed)
				(copperpour not_allowed)
				(footprints allowed)
			)
			(placement
				(enabled no)
				(sheetname "")
			)
			(fill
				(thermal_gap 0.5)
				(thermal_bridge_width 0.5)
				(island_removal_mode 0)
			)
			(polygon
				(pts
					(xy 48.264572 -54.053232) (xy 52.582572 -54.053232) (xy 52.582572 -54.561232) (xy 48.264572 -54.561232)
				)
			)
		)
	)
	(footprint ""
		(layer "F.Cu")
		(at 345.059 -70.739 -90)
		(property "Reference" "PR160"
			(at 0 0 270)
			(layer "F.SilkS")
			(hide yes)
			(effects
				(font
					(size 1.27 1.27)
				)
			)
		)
		(property "Value" "475KR2F-GP"
			(at 0.064008 -3.993896 270)
			(unlocked yes)
			(layer "F.Fab")
			(hide yes)
			(effects
				(font
					(size 1.016 1.016)
					(thickness 0.1524)
				)
			)
		)
		(property "Device Type" "R402H16"
			(at 0.064008 -5.517896 270)
			(unlocked yes)
			(layer "F.Fab")
			(hide yes)
			(effects
				(font
					(size 1.016 1.016)
					(thickness 0.1524)
				)
			)
		)
		(duplicate_pad_numbers_are_jumpers no)
		(fp_line
			(start -0.508 -0.9398)
			(end -0.508 0.9398)
			(stroke
				(width 0.1524)
				(type default)
			)
			(layer "F.SilkS")
		)
		(fp_line
			(start 0.508 -0.9398)
			(end -0.508 -0.9398)
			(stroke
				(width 0.1524)
				(type default)
			)
			(layer "F.SilkS")
		)
		(fp_rect
			(start -0.508 0.9398)
			(end 0.508 -0.9398)
			(stroke
				(width 0)
				(type default)
			)
			(fill no)
			(layer "F.CrtYd")
		)
		(fp_rect
			(start -0.508 0.9398)
			(end 0.508 -0.9398)
			(stroke
				(width 0)
				(type default)
			)
			(fill no)
			(layer "F.Fab")
		)
		(pad "1" smd custom
			(at 0 -0.4445 270)
			(size 0.1397 0.1397)
			(layers "F.Cu" "F.Mask" "F.Paste")
			(net "P0V9_E_PG")
			(options
				(clearance outline)
				(anchor circle)
			)
			(primitives
				(gr_poly
					(pts
						(arc
							(start -0.1778 -0.2794)
							(mid -0.249642 -0.249642)
							(end -0.2794 -0.1778)
						)
						(arc
							(start -0.2794 0.1778)
							(mid -0.249642 0.249642)
							(end -0.1778 0.2794)
						)
						(arc
							(start 0.1778 0.2794)
							(mid 0.249642 0.249642)
							(end 0.2794 0.1778)
						)
						(arc
							(start 0.2794 -0.1778)
							(mid 0.249642 -0.249642)
							(end 0.1778 -0.2794)
						)
					)
					(width 0)
					(fill yes)
				)
			)
		)
		(pad "2" smd custom
			(at 0 0.4445 270)
			(size 0.1397 0.1397)
			(layers "F.Cu" "F.Mask" "F.Paste")
			(net "P0V9_E_MODE")
			(options
				(clearance outline)
				(anchor circle)
			)
			(primitives
				(gr_poly
					(pts
						(arc
							(start -0.1778 -0.2794)
							(mid -0.249642 -0.249642)
							(end -0.2794 -0.1778)
						)
						(arc
							(start -0.2794 0.1778)
							(mid -0.249642 0.249642)
							(end -0.1778 0.2794)
						)
						(arc
							(start 0.1778 0.2794)
							(mid 0.249642 0.249642)
							(end 0.2794 0.1778)
						)
						(arc
							(start 0.2794 -0.1778)
							(mid 0.249642 -0.249642)
							(end 0.1778 -0.2794)
						)
					)
					(width 0)
					(fill yes)
				)
			)
		)
	)
	(footprint ""
		(layer "F.Cu")
		(at 61.595 -131.953 180)
		(property "Reference" "R315"
			(at 0 0 180)
			(layer "F.SilkS")
			(hide yes)
			(effects
				(font
					(size 1.27 1.27)
				)
			)
		)
		(property "Value" "0R2J-2-GP"
			(at 0.064008 -3.993896 180)
			(unlocked yes)
			(layer "F.Fab")
			(hide yes)
			(effects
				(font
					(size 1.016 1.016)
					(thickness 0.1524)
				)
			)
		)
		(property "Device Type" "R402H16"
			(at 0.064008 -5.517896 180)
			(unlocked yes)
			(layer "F.Fab")
			(hide yes)
			(effects
				(font
					(size 1.016 1.016)
					(thickness 0.1524)
				)
			)
		)
		(duplicate_pad_numbers_are_jumpers no)
		(fp_line
			(start 0.508 -0.9398)
			(end -0.508 -0.9398)
			(stroke
				(width 0.1524)
				(type default)
			)
			(layer "F.SilkS")
		)
		(fp_line
			(start -0.508 -0.9398)
			(end -0.508 0.9398)
			(stroke
				(width 0.1524)
				(type default)
			)
			(layer "F.SilkS")
		)
		(fp_rect
			(start -0.508 0.9398)
			(end 0.508 -0.9398)
			(stroke
				(width 0)
				(type default)
			)
			(fill no)
			(layer "F.CrtYd")
		)
		(fp_rect
			(start -0.508 0.9398)
			(end 0.508 -0.9398)
			(stroke
				(width 0)
				(type default)
			)
			(fill no)
			(layer "F.Fab")
		)
		(pad "1" smd custom
			(at 0 -0.4445 180)
			(size 0.1397 0.1397)
			(layers "F.Cu" "F.Mask" "F.Paste")
			(net "ADC_12V")
			(options
				(clearance outline)
				(anchor circle)
			)
			(primitives
				(gr_poly
					(pts
						(arc
							(start -0.1778 -0.2794)
							(mid -0.249642 -0.249642)
							(end -0.2794 -0.1778)
						)
						(arc
							(start -0.2794 0.1778)
							(mid -0.249642 0.249642)
							(end -0.1778 0.2794)
						)
						(arc
							(start 0.1778 0.2794)
							(mid 0.249642 0.249642)
							(end 0.2794 0.1778)
						)
						(arc
							(start 0.2794 -0.1778)
							(mid 0.249642 -0.249642)
							(end 0.1778 -0.2794)
						)
					)
					(width 0)
					(fill yes)
				)
			)
		)
		(pad "2" smd custom
			(at 0 0.4445 180)
			(size 0.1397 0.1397)
			(layers "F.Cu" "F.Mask" "F.Paste")
			(net "ADC0_12V_BMC")
			(options
				(clearance outline)
				(anchor circle)
			)
			(primitives
				(gr_poly
					(pts
						(arc
							(start -0.1778 -0.2794)
							(mid -0.249642 -0.249642)
							(end -0.2794 -0.1778)
						)
						(arc
							(start -0.2794 0.1778)
							(mid -0.249642 0.249642)
							(end -0.1778 0.2794)
						)
						(arc
							(start 0.1778 0.2794)
							(mid 0.249642 0.249642)
							(end 0.2794 0.1778)
						)
						(arc
							(start 0.2794 -0.1778)
							(mid 0.249642 -0.249642)
							(end 0.1778 -0.2794)
						)
					)
					(width 0)
					(fill yes)
				)
			)
		)
	)
	(footprint ""
		(layer "F.Cu")
		(at 67.808094 -212.420454 180)
		(property "Reference" "C356"
			(at 0 0 180)
			(layer "F.SilkS")
			(hide yes)
			(effects
				(font
					(size 1.27 1.27)
				)
			)
		)
		(property "Value" "SCD22U10V2KX-1GP"
			(at 1.1811 -2.7051 180)
			(unlocked yes)
			(layer "F.Fab")
			(hide yes)
			(effects
				(font
					(size 1.016 1.016)
					(thickness 0.1524)
				)
			)
		)
		(property "Device Type" "C402H22"
			(at 1.1811 -4.2291 180)
			(unlocked yes)
			(layer "F.Fab")
			(hide yes)
			(effects
				(font
					(size 1.016 1.016)
					(thickness 0.1524)
				)
			)
		)
		(duplicate_pad_numbers_are_jumpers no)
		(fp_rect
			(start -0.4318 0.9525)
			(end 0.4318 -0.9525)
			(stroke
				(width 0)
				(type default)
			)
			(fill no)
			(layer "F.CrtYd")
		)
		(fp_rect
			(start -0.4318 0.9525)
			(end 0.4318 -0.9525)
			(stroke
				(width 0)
				(type default)
			)
			(fill no)
			(layer "F.Fab")
		)
		(pad "1" smd custom
			(at 0 -0.4445 180)
			(size 0.1524 0.1524)
			(layers "F.Cu" "F.Mask" "F.Paste")
			(net "PCIE_TX_CAP_N70")
			(options
				(clearance outline)
				(anchor circle)
			)
			(primitives
				(gr_poly
					(pts
						(arc
							(start 0.3048 -0.2032)
							(mid 0.275042 -0.275042)
							(end 0.2032 -0.3048)
						)
						(arc
							(start -0.2032 -0.3048)
							(mid -0.275042 -0.275042)
							(end -0.3048 -0.2032)
						)
						(arc
							(start -0.3048 0.2032)
							(mid -0.275042 0.275042)
							(end -0.2032 0.3048)
						)
						(arc
							(start 0.2032 0.3048)
							(mid 0.275042 0.275042)
							(end 0.3048 0.2032)
						)
					)
					(width 0)
					(fill yes)
				)
			)
		)
		(pad "2" smd custom
			(at 0 0.4445 180)
			(size 0.1524 0.1524)
			(layers "F.Cu" "F.Mask" "F.Paste")
			(net "PCIE_TX_N70")
			(options
				(clearance outline)
				(anchor circle)
			)
			(primitives
				(gr_poly
					(pts
						(arc
							(start 0.3048 -0.2032)
							(mid 0.275042 -0.275042)
							(end 0.2032 -0.3048)
						)
						(arc
							(start -0.2032 -0.3048)
							(mid -0.275042 -0.275042)
							(end -0.3048 -0.2032)
						)
						(arc
							(start -0.3048 0.2032)
							(mid -0.275042 0.275042)
							(end -0.2032 0.3048)
						)
						(arc
							(start 0.2032 0.3048)
							(mid 0.275042 0.275042)
							(end 0.3048 0.2032)
						)
					)
					(width 0)
					(fill yes)
				)
			)
		)
	)
	(footprint ""
		(layer "F.Cu")
		(at 60.028074 -58.94832)
		(property "Reference" "R267"
			(at 0 0 0)
			(layer "F.SilkS")
			(hide yes)
			(effects
				(font
					(size 1.27 1.27)
				)
			)
		)
		(property "Value" "2K2R2J-2-GP"
			(at 0.064008 -3.993896 0)
			(unlocked yes)
			(layer "F.Fab")
			(hide yes)
			(effects
				(font
					(size 1.016 1.016)
					(thickness 0.1524)
				)
			)
		)
		(property "Device Type" "R402H16"
			(at 0.064008 -5.517896 0)
			(unlocked yes)
			(layer "F.Fab")
			(hide yes)
			(effects
				(font
					(size 1.016 1.016)
					(thickness 0.1524)
				)
			)
		)
		(duplicate_pad_numbers_are_jumpers no)
		(fp_line
			(start -0.508 -0.9398)
			(end -0.508 0.9398)
			(stroke
				(width 0.1524)
				(type default)
			)
			(layer "F.SilkS")
		)
		(fp_line
			(start 0.508 -0.9398)
			(end -0.508 -0.9398)
			(stroke
				(width 0.1524)
				(type default)
			)
			(layer "F.SilkS")
		)
		(fp_rect
			(start -0.508 0.9398)
			(end 0.508 -0.9398)
			(stroke
				(width 0)
				(type default)
			)
			(fill no)
			(layer "F.CrtYd")
		)
		(fp_rect
			(start -0.508 0.9398)
			(end 0.508 -0.9398)
			(stroke
				(width 0)
				(type default)
			)
			(fill no)
			(layer "F.Fab")
		)
		(pad "1" smd custom
			(at 0 -0.4445)
			(size 0.1397 0.1397)
			(layers "F.Cu" "F.Mask" "F.Paste")
			(net "FLA_WPN")
			(options
				(clearance outline)
				(anchor circle)
			)
			(primitives
				(gr_poly
					(pts
						(arc
							(start -0.1778 -0.2794)
							(mid -0.249642 -0.249642)
							(end -0.2794 -0.1778)
						)
						(arc
							(start -0.2794 0.1778)
							(mid -0.249642 0.249642)
							(end -0.1778 0.2794)
						)
						(arc
							(start 0.1778 0.2794)
							(mid 0.249642 0.249642)
							(end 0.2794 0.1778)
						)
						(arc
							(start 0.2794 -0.1778)
							(mid 0.249642 -0.249642)
							(end 0.1778 -0.2794)
						)
					)
					(width 0)
					(fill yes)
				)
			)
		)
		(pad "2" smd custom
			(at 0 0.4445)
			(size 0.1397 0.1397)
			(layers "F.Cu" "F.Mask" "F.Paste")
			(net "GND")
			(options
				(clearance outline)
				(anchor circle)
			)
			(primitives
				(gr_poly
					(pts
						(arc
							(start -0.1778 -0.2794)
							(mid -0.249642 -0.249642)
							(end -0.2794 -0.1778)
						)
						(arc
							(start -0.2794 0.1778)
							(mid -0.249642 0.249642)
							(end -0.1778 0.2794)
						)
						(arc
							(start 0.1778 0.2794)
							(mid 0.249642 0.249642)
							(end 0.2794 0.1778)
						)
						(arc
							(start 0.2794 -0.1778)
							(mid 0.249642 -0.249642)
							(end 0.1778 -0.2794)
						)
					)
					(width 0)
					(fill yes)
				)
			)
		)
	)
)
